(kicad_pcb
	(version 20260206)
	(generator "pcbnew")
	(generator_version "10.0")
	(general
		(thickness 1.6)
		(legacy_teardrops no)
	)
	(paper "A4")
	(title_block
		(title "01162023_DA0F0TEBIF0_F0T_Expander_BD_F_brd_V02_OCP.brd")
		(comment 1 "Grand Teton / footprints 217-223 of 9728")
	)
	(layers
		(0 "F.Cu" signal "TOP")
		(4 "In1.Cu" signal "GND")
		(6 "In2.Cu" signal "VCC")
		(8 "In3.Cu" signal "VCC1")
		(10 "In4.Cu" signal "GND1")
		(12 "In5.Cu" signal "IN1")
		(14 "In6.Cu" signal "GND2")
		(16 "In7.Cu" signal "IN2")
		(18 "In8.Cu" signal "GND3")
		(20 "In9.Cu" signal "IN3")
		(22 "In10.Cu" signal "GND4")
		(24 "In11.Cu" signal "IN4")
		(26 "In12.Cu" signal "GND5")
		(28 "In13.Cu" signal "IN5")
		(30 "In14.Cu" signal "GND6")
		(32 "In15.Cu" signal "IN6")
		(34 "In16.Cu" signal "GND7")
		(2 "B.Cu" signal "BOTTOM")
		(9 "F.Adhes" user "F.Adhesive")
		(11 "B.Adhes" user "B.Adhesive")
		(13 "F.Paste" user "Package Geometry/Pastemask Top")
		(15 "B.Paste" user "Package Geometry/Pastemask Bottom")
		(5 "F.SilkS" user "Ref Des/Silkscreen Top")
		(7 "B.SilkS" user "Ref Des/Silkscreen Bottom")
		(1 "F.Mask" user "Board Geometry/Soldermask Top")
		(3 "B.Mask" user "Board Geometry/Soldermask Bottom")
		(17 "Dwgs.User" user "User.Drawings")
		(19 "Cmts.User" user "User.Comments")
		(21 "Eco1.User" user "User.Eco1")
		(23 "Eco2.User" user "User.Eco2")
		(25 "Edge.Cuts" user "Board Geometry/Outline")
		(27 "Margin" user)
		(31 "F.CrtYd" user "Package Geometry/Place Bound Top")
		(29 "B.CrtYd" user "Package Geometry/Place Bound Bottom")
		(35 "F.Fab" user "Ref Des/Assembly Top")
		(33 "B.Fab" user "Ref Des/Assembly Bottom")
	)
	(footprint ""
		(layer "F.Cu")
		(at 357.746808 -154.256994)
		(property "Reference" "PC830"
			(at 0 0 0)
			(layer "F.SilkS")
			(hide yes)
			(effects
				(font
					(size 1.27 1.27)
				)
			)
		)
		(property "Value" ""
			(at 0 0 0)
			(layer "F.Fab")
			(effects
				(font
					(size 1.27 1.27)
				)
			)
		)
		(duplicate_pad_numbers_are_jumpers no)
		(fp_line
			(start -1.2954 -0.5842)
			(end 1.2954 -0.5842)
			(stroke
				(width 0.1524)
				(type default)
			)
			(layer "F.SilkS")
		)
		(fp_line
			(start -1.2954 0.5842)
			(end -1.2954 -0.5842)
			(stroke
				(width 0.1524)
				(type default)
			)
			(layer "F.SilkS")
		)
		(fp_line
			(start 1.2954 -0.5842)
			(end 1.2954 0.5842)
			(stroke
				(width 0.1524)
				(type default)
			)
			(layer "F.SilkS")
		)
		(fp_line
			(start 1.2954 0.5842)
			(end -1.2954 0.5842)
			(stroke
				(width 0.1524)
				(type default)
			)
			(layer "F.SilkS")
		)
		(fp_line
			(start -1.1938 -0.4064)
			(end -0.8636 -0.4064)
			(stroke
				(width 0.1)
				(type default)
			)
			(layer "F.Fab")
		)
		(fp_line
			(start -1.1938 0.4064)
			(end -1.1938 -0.4064)
			(stroke
				(width 0.1)
				(type default)
			)
			(layer "F.Fab")
		)
		(fp_line
			(start -0.8636 -0.4572)
			(end 0.8636 -0.4572)
			(stroke
				(width 0.1)
				(type default)
			)
			(layer "F.Fab")
		)
		(fp_line
			(start -0.8636 -0.4064)
			(end -0.8636 -0.4572)
			(stroke
				(width 0.1)
				(type default)
			)
			(layer "F.Fab")
		)
		(fp_line
			(start -0.8636 0.4064)
			(end -1.1938 0.4064)
			(stroke
				(width 0.1)
				(type default)
			)
			(layer "F.Fab")
		)
		(fp_line
			(start -0.8636 0.4572)
			(end -0.8636 0.4064)
			(stroke
				(width 0.1)
				(type default)
			)
			(layer "F.Fab")
		)
		(fp_line
			(start 0.8636 -0.4572)
			(end 0.8636 -0.4064)
			(stroke
				(width 0.1)
				(type default)
			)
			(layer "F.Fab")
		)
		(fp_line
			(start 0.8636 -0.4064)
			(end 1.1938 -0.4064)
			(stroke
				(width 0.1)
				(type default)
			)
			(layer "F.Fab")
		)
		(fp_line
			(start 0.8636 0.4064)
			(end 0.8636 0.4572)
			(stroke
				(width 0.1)
				(type default)
			)
			(layer "F.Fab")
		)
		(fp_line
			(start 0.8636 0.4572)
			(end -0.8636 0.4572)
			(stroke
				(width 0.1)
				(type default)
			)
			(layer "F.Fab")
		)
		(fp_line
			(start 1.1938 -0.4064)
			(end 1.1938 0.4064)
			(stroke
				(width 0.1)
				(type default)
			)
			(layer "F.Fab")
		)
		(fp_line
			(start 1.1938 0.4064)
			(end 0.8636 0.4064)
			(stroke
				(width 0.1)
				(type default)
			)
			(layer "F.Fab")
		)
		(pad "1" smd rect
			(at -0.7366 0 270)
			(size 0.7112 0.8128)
			(layers "F.Cu" "F.Mask" "F.Paste")
			(net "GND")
		)
		(pad "2" smd rect
			(at 0.7366 0 270)
			(size 0.7112 0.8128)
			(layers "F.Cu" "F.Mask" "F.Paste")
			(net "P12V_NIC6_CO_AVIN_PD")
		)
	)
	(footprint ""
		(layer "F.Cu")
		(at 3.047746 -34.890456 90)
		(property "Reference" "R1643"
			(at 0 0 90)
			(layer "F.SilkS")
			(hide yes)
			(effects
				(font
					(size 1.27 1.27)
				)
			)
		)
		(property "Value" ""
			(at 0 0 90)
			(layer "F.Fab")
			(effects
				(font
					(size 1.27 1.27)
				)
			)
		)
		(duplicate_pad_numbers_are_jumpers no)
		(fp_line
			(start 0.7874 -0.4064)
			(end 0.7874 0.4064)
			(stroke
				(width 0.1524)
				(type default)
			)
			(layer "F.SilkS")
		)
		(fp_line
			(start -0.7874 -0.4064)
			(end 0.7874 -0.4064)
			(stroke
				(width 0.1524)
				(type default)
			)
			(layer "F.SilkS")
		)
		(fp_line
			(start 0.7874 0.4064)
			(end -0.7874 0.4064)
			(stroke
				(width 0.1524)
				(type default)
			)
			(layer "F.SilkS")
		)
		(fp_line
			(start -0.7874 0.4064)
			(end -0.7874 -0.4064)
			(stroke
				(width 0.1524)
				(type default)
			)
			(layer "F.SilkS")
		)
		(fp_line
			(start -0.12065 -0.305054)
			(end -0.12065 -0.2794)
			(stroke
				(width 0.1)
				(type default)
			)
			(layer "F.Fab")
		)
		(fp_line
			(start -0.67945 -0.305054)
			(end -0.12065 -0.305054)
			(stroke
				(width 0.1)
				(type default)
			)
			(layer "F.Fab")
		)
		(fp_line
			(start 0.67945 -0.3048)
			(end 0.67945 0.3048)
			(stroke
				(width 0.1)
				(type default)
			)
			(layer "F.Fab")
		)
		(fp_line
			(start 0.12065 -0.3048)
			(end 0.67945 -0.3048)
			(stroke
				(width 0.1)
				(type default)
			)
			(layer "F.Fab")
		)
		(fp_line
			(start 0.12065 -0.2794)
			(end 0.12065 -0.3048)
			(stroke
				(width 0.1)
				(type default)
			)
			(layer "F.Fab")
		)
		(fp_line
			(start -0.12065 -0.2794)
			(end 0.12065 -0.2794)
			(stroke
				(width 0.1)
				(type default)
			)
			(layer "F.Fab")
		)
		(fp_line
			(start 0.120396 0.2794)
			(end -0.12065 0.2794)
			(stroke
				(width 0.1)
				(type default)
			)
			(layer "F.Fab")
		)
		(fp_line
			(start -0.12065 0.2794)
			(end -0.12065 0.3048)
			(stroke
				(width 0.1)
				(type default)
			)
			(layer "F.Fab")
		)
		(fp_line
			(start 0.67945 0.3048)
			(end 0.120396 0.3048)
			(stroke
				(width 0.1)
				(type default)
			)
			(layer "F.Fab")
		)
		(fp_line
			(start 0.120396 0.3048)
			(end 0.120396 0.2794)
			(stroke
				(width 0.1)
				(type default)
			)
			(layer "F.Fab")
		)
		(fp_line
			(start -0.12065 0.3048)
			(end -0.67945 0.3048)
			(stroke
				(width 0.1)
				(type default)
			)
			(layer "F.Fab")
		)
		(fp_line
			(start -0.67945 0.3048)
			(end -0.67945 -0.305054)
			(stroke
				(width 0.1)
				(type default)
			)
			(layer "F.Fab")
		)
		(pad "1" smd circle
			(at -0.40005 0 90)
			(size 0 0)
			(layers "F.Cu" "F.Mask" "F.Paste")
			(net "SMB_BIC_I2C9_MUX0_SSD0_R_SCL")
		)
		(pad "2" smd circle
			(at 0.40005 0 90)
			(size 0 0)
			(layers "F.Cu" "F.Mask" "F.Paste")
			(net "SMB_ISO_SSD0_SCL")
		)
	)
	(footprint ""
		(layer "F.Cu")
		(at 73.96099 -37.951156)
		(property "Reference" "Q136"
			(at -0.09779 -1.874774 0)
			(unlocked yes)
			(layer "F.SilkS")
			(effects
				(font
					(size 0.7874 0.5842)
					(thickness 0.1524)
				)
			)
		)
		(property "Value" ""
			(at 0 0 0)
			(layer "F.Fab")
			(effects
				(font
					(size 1.27 1.27)
				)
			)
		)
		(duplicate_pad_numbers_are_jumpers no)
		(fp_line
			(start -1.376172 -1.199896)
			(end -0.508 -1.199896)
			(stroke
				(width 0.1524)
				(type default)
			)
			(layer "F.SilkS")
		)
		(fp_line
			(start -1.376172 1.199896)
			(end -1.376172 -1.199896)
			(stroke
				(width 0.1524)
				(type default)
			)
			(layer "F.SilkS")
		)
		(fp_line
			(start -0.508 -1.199896)
			(end 0 -0.762)
			(stroke
				(width 0.1524)
				(type default)
			)
			(layer "F.SilkS")
		)
		(fp_line
			(start 0 -0.762)
			(end 0.508 -1.199896)
			(stroke
				(width 0.1524)
				(type default)
			)
			(layer "F.SilkS")
		)
		(fp_line
			(start 0.508 -1.199896)
			(end 1.376172 -1.199896)
			(stroke
				(width 0.1524)
				(type default)
			)
			(layer "F.SilkS")
		)
		(fp_line
			(start 1.376172 -1.199896)
			(end 1.376172 1.199896)
			(stroke
				(width 0.1524)
				(type default)
			)
			(layer "F.SilkS")
		)
		(fp_line
			(start 1.376172 1.199896)
			(end -1.376172 1.199896)
			(stroke
				(width 0.1524)
				(type default)
			)
			(layer "F.SilkS")
		)
		(fp_poly
			(pts
				(xy -1.64084 -1.123188) (xy -1.91008 -1.931416) (xy -2.449068 -1.392428)
			)
			(stroke
				(width 0)
				(type default)
			)
			(fill yes)
			(layer "F.SilkS")
		)
		(fp_line
			(start -0.674878 -1.100074)
			(end 0.674878 -1.100074)
			(stroke
				(width 0.1)
				(type default)
			)
			(layer "F.Fab")
		)
		(fp_line
			(start -0.674878 1.100074)
			(end -0.674878 -1.100074)
			(stroke
				(width 0.1)
				(type default)
			)
			(layer "F.Fab")
		)
		(fp_line
			(start 0.674878 -1.100074)
			(end 0.674878 1.100074)
			(stroke
				(width 0.1)
				(type default)
			)
			(layer "F.Fab")
		)
		(fp_line
			(start 0.674878 1.100074)
			(end -0.674878 1.100074)
			(stroke
				(width 0.1)
				(type default)
			)
			(layer "F.Fab")
		)
		(fp_poly
			(pts
				(xy -1.4605 -0.7493) (xy -2.2225 -1.1303) (xy -2.2225 -0.3683)
			)
			(stroke
				(width 0)
				(type default)
			)
			(fill yes)
			(layer "F.Fab")
		)
		(pad "1" smd rect
			(at -0.899922 -0.750062 270)
			(size 0.6096 0.6096)
			(layers "F.Cu" "F.Mask" "F.Paste")
			(net "GND")
		)
		(pad "2" smd rect
			(at -0.899922 0 270)
			(size 0.4064 0.6096)
			(layers "F.Cu" "F.Mask" "F.Paste")
			(net "P3V3_SSD3_PG_G1")
		)
		(pad "3" smd rect
			(at -0.899922 0.750062 270)
			(size 0.6096 0.6096)
			(layers "F.Cu" "F.Mask" "F.Paste")
			(net "PWRGD_P3V3_SSD3_D")
		)
		(pad "4" smd rect
			(at 0.899922 0.750062 270)
			(size 0.6096 0.6096)
			(layers "F.Cu" "F.Mask" "F.Paste")
			(net "GND")
		)
		(pad "5" smd rect
			(at 0.899922 0 270)
			(size 0.4064 0.6096)
			(layers "F.Cu" "F.Mask" "F.Paste")
			(net "P3V3_SSD3_PG_G2")
		)
		(pad "6" smd rect
			(at 0.899922 -0.750062 270)
			(size 0.6096 0.6096)
			(layers "F.Cu" "F.Mask" "F.Paste")
			(net "P3V3_SSD3_PG_G2")
		)
	)
	(footprint ""
		(layer "F.Cu")
		(at 217.235786 -215.254586 180)
		(property "Reference" "R1505"
			(at 0 0 180)
			(layer "F.SilkS")
			(hide yes)
			(effects
				(font
					(size 1.27 1.27)
				)
			)
		)
		(property "Value" ""
			(at 0 0 180)
			(layer "F.Fab")
			(effects
				(font
					(size 1.27 1.27)
				)
			)
		)
		(duplicate_pad_numbers_are_jumpers no)
		(fp_line
			(start 0.7874 0.4064)
			(end -0.7874 0.4064)
			(stroke
				(width 0.1524)
				(type default)
			)
			(layer "F.SilkS")
		)
		(fp_line
			(start 0.7874 -0.4064)
			(end 0.7874 0.4064)
			(stroke
				(width 0.1524)
				(type default)
			)
			(layer "F.SilkS")
		)
		(fp_line
			(start -0.7874 0.4064)
			(end -0.7874 -0.4064)
			(stroke
				(width 0.1524)
				(type default)
			)
			(layer "F.SilkS")
		)
		(fp_line
			(start -0.7874 -0.4064)
			(end 0.7874 -0.4064)
			(stroke
				(width 0.1524)
				(type default)
			)
			(layer "F.SilkS")
		)
		(fp_line
			(start 0.67945 0.3048)
			(end 0.120396 0.3048)
			(stroke
				(width 0.1)
				(type default)
			)
			(layer "F.Fab")
		)
		(fp_line
			(start 0.67945 -0.3048)
			(end 0.67945 0.3048)
			(stroke
				(width 0.1)
				(type default)
			)
			(layer "F.Fab")
		)
		(fp_line
			(start 0.12065 -0.2794)
			(end 0.12065 -0.3048)
			(stroke
				(width 0.1)
				(type default)
			)
			(layer "F.Fab")
		)
		(fp_line
			(start 0.12065 -0.3048)
			(end 0.67945 -0.3048)
			(stroke
				(width 0.1)
				(type default)
			)
			(layer "F.Fab")
		)
		(fp_line
			(start 0.120396 0.3048)
			(end 0.120396 0.2794)
			(stroke
				(width 0.1)
				(type default)
			)
			(layer "F.Fab")
		)
		(fp_line
			(start 0.120396 0.2794)
			(end -0.12065 0.2794)
			(stroke
				(width 0.1)
				(type default)
			)
			(layer "F.Fab")
		)
		(fp_line
			(start -0.12065 0.3048)
			(end -0.67945 0.3048)
			(stroke
				(width 0.1)
				(type default)
			)
			(layer "F.Fab")
		)
		(fp_line
			(start -0.12065 0.2794)
			(end -0.12065 0.3048)
			(stroke
				(width 0.1)
				(type default)
			)
			(layer "F.Fab")
		)
		(fp_line
			(start -0.12065 -0.2794)
			(end 0.12065 -0.2794)
			(stroke
				(width 0.1)
				(type default)
			)
			(layer "F.Fab")
		)
		(fp_line
			(start -0.12065 -0.305054)
			(end -0.12065 -0.2794)
			(stroke
				(width 0.1)
				(type default)
			)
			(layer "F.Fab")
		)
		(fp_line
			(start -0.67945 0.3048)
			(end -0.67945 -0.305054)
			(stroke
				(width 0.1)
				(type default)
			)
			(layer "F.Fab")
		)
		(fp_line
			(start -0.67945 -0.305054)
			(end -0.12065 -0.305054)
			(stroke
				(width 0.1)
				(type default)
			)
			(layer "F.Fab")
		)
		(pad "1" smd circle
			(at -0.40005 0 180)
			(size 0 0)
			(layers "F.Cu" "F.Mask" "F.Paste")
			(net "SMB_NIC7_SDA")
		)
		(pad "2" smd circle
			(at 0.40005 0 180)
			(size 0 0)
			(layers "F.Cu" "F.Mask" "F.Paste")
			(net "SMB_NIC7_R_SDA")
		)
	)
	(footprint ""
		(layer "F.Cu")
		(at 435.055772 -356.244906 90)
		(property "Reference" "C801"
			(at 0 0 90)
			(layer "F.SilkS")
			(hide yes)
			(effects
				(font
					(size 1.27 1.27)
				)
			)
		)
		(property "Value" ""
			(at 0 0 90)
			(layer "F.Fab")
			(effects
				(font
					(size 1.27 1.27)
				)
			)
		)
		(duplicate_pad_numbers_are_jumpers no)
		(fp_line
			(start 0.299974 -0.150114)
			(end 0.299974 0.150114)
			(stroke
				(width 0.1)
				(type default)
			)
			(layer "F.Fab")
		)
		(fp_line
			(start -0.299974 -0.150114)
			(end 0.299974 -0.150114)
			(stroke
				(width 0.1)
				(type default)
			)
			(layer "F.Fab")
		)
		(fp_line
			(start 0.299974 0.150114)
			(end -0.299974 0.150114)
			(stroke
				(width 0.1)
				(type default)
			)
			(layer "F.Fab")
		)
		(fp_line
			(start -0.299974 0.150114)
			(end -0.299974 -0.150114)
			(stroke
				(width 0.1)
				(type default)
			)
			(layer "F.Fab")
		)
		(pad "1" smd rect
			(at -0.2667 0 90)
			(size 0.3048 0.381)
			(layers "F.Cu" "F.Mask" "F.Paste")
			(net "P5E_PEX3_STN7_TX_DN<124>")
		)
		(pad "2" smd rect
			(at 0.2667 0 90)
			(size 0.3048 0.381)
			(layers "F.Cu" "F.Mask" "F.Paste")
			(net "P5E_PEX3_STN7_TX_C_DN<124>")
		)
	)
	(footprint ""
		(layer "F.Cu")
		(at 186.5376 -408.0764 180)
		(property "Reference" "R4416"
			(at 0 0 180)
			(layer "F.SilkS")
			(hide yes)
			(effects
				(font
					(size 1.27 1.27)
				)
			)
		)
		(property "Value" ""
			(at 0 0 180)
			(layer "F.Fab")
			(effects
				(font
					(size 1.27 1.27)
				)
			)
		)
		(duplicate_pad_numbers_are_jumpers no)
		(fp_line
			(start 0.7874 0.4064)
			(end -0.7874 0.4064)
			(stroke
				(width 0.1524)
				(type default)
			)
			(layer "F.SilkS")
		)
		(fp_line
			(start 0.7874 -0.4064)
			(end 0.7874 0.4064)
			(stroke
				(width 0.1524)
				(type default)
			)
			(layer "F.SilkS")
		)
		(fp_line
			(start -0.7874 0.4064)
			(end -0.7874 -0.4064)
			(stroke
				(width 0.1524)
				(type default)
			)
			(layer "F.SilkS")
		)
		(fp_line
			(start -0.7874 -0.4064)
			(end 0.7874 -0.4064)
			(stroke
				(width 0.1524)
				(type default)
			)
			(layer "F.SilkS")
		)
		(fp_line
			(start 0.67945 0.3048)
			(end 0.120396 0.3048)
			(stroke
				(width 0.1)
				(type default)
			)
			(layer "F.Fab")
		)
		(fp_line
			(start 0.67945 -0.3048)
			(end 0.67945 0.3048)
			(stroke
				(width 0.1)
				(type default)
			)
			(layer "F.Fab")
		)
		(fp_line
			(start 0.12065 -0.2794)
			(end 0.12065 -0.3048)
			(stroke
				(width 0.1)
				(type default)
			)
			(layer "F.Fab")
		)
		(fp_line
			(start 0.12065 -0.3048)
			(end 0.67945 -0.3048)
			(stroke
				(width 0.1)
				(type default)
			)
			(layer "F.Fab")
		)
		(fp_line
			(start 0.120396 0.3048)
			(end 0.120396 0.2794)
			(stroke
				(width 0.1)
				(type default)
			)
			(layer "F.Fab")
		)
		(fp_line
			(start 0.120396 0.2794)
			(end -0.12065 0.2794)
			(stroke
				(width 0.1)
				(type default)
			)
			(layer "F.Fab")
		)
		(fp_line
			(start -0.12065 0.3048)
			(end -0.67945 0.3048)
			(stroke
				(width 0.1)
				(type default)
			)
			(layer "F.Fab")
		)
		(fp_line
			(start -0.12065 0.2794)
			(end -0.12065 0.3048)
			(stroke
				(width 0.1)
				(type default)
			)
			(layer "F.Fab")
		)
		(fp_line
			(start -0.12065 -0.2794)
			(end 0.12065 -0.2794)
			(stroke
				(width 0.1)
				(type default)
			)
			(layer "F.Fab")
		)
		(fp_line
			(start -0.12065 -0.305054)
			(end -0.12065 -0.2794)
			(stroke
				(width 0.1)
				(type default)
			)
			(layer "F.Fab")
		)
		(fp_line
			(start -0.67945 0.3048)
			(end -0.67945 -0.305054)
			(stroke
				(width 0.1)
				(type default)
			)
			(layer "F.Fab")
		)
		(fp_line
			(start -0.67945 -0.305054)
			(end -0.12065 -0.305054)
			(stroke
				(width 0.1)
				(type default)
			)
			(layer "F.Fab")
		)
		(pad "1" smd circle
			(at -0.40005 0 180)
			(size 0 0)
			(layers "F.Cu" "F.Mask" "F.Paste")
			(net "A_P12V_AUX_FPH_GATE")
		)
		(pad "2" smd circle
			(at 0.40005 0 180)
			(size 0 0)
			(layers "F.Cu" "F.Mask" "F.Paste")
			(net "P3V3_AUX")
		)
	)
	(footprint ""
		(layer "F.Cu")
		(at 399.14322 -356.244906 90)
		(property "Reference" "C748"
			(at 0 0 90)
			(layer "F.SilkS")
			(hide yes)
			(effects
				(font
					(size 1.27 1.27)
				)
			)
		)
		(property "Value" ""
			(at 0 0 90)
			(layer "F.Fab")
			(effects
				(font
					(size 1.27 1.27)
				)
			)
		)
		(duplicate_pad_numbers_are_jumpers no)
		(fp_line
			(start 0.299974 -0.150114)
			(end 0.299974 0.150114)
			(stroke
				(width 0.1)
				(type default)
			)
			(layer "F.Fab")
		)
		(fp_line
			(start -0.299974 -0.150114)
			(end 0.299974 -0.150114)
			(stroke
				(width 0.1)
				(type default)
			)
			(layer "F.Fab")
		)
		(fp_line
			(start 0.299974 0.150114)
			(end -0.299974 0.150114)
			(stroke
				(width 0.1)
				(type default)
			)
			(layer "F.Fab")
		)
		(fp_line
			(start -0.299974 0.150114)
			(end -0.299974 -0.150114)
			(stroke
				(width 0.1)
				(type default)
			)
			(layer "F.Fab")
		)
		(pad "1" smd rect
			(at -0.2667 0 90)
			(size 0.3048 0.381)
			(layers "F.Cu" "F.Mask" "F.Paste")
			(net "P5E_PEX3_STN5_TX_DP<86>")
		)
		(pad "2" smd rect
			(at 0.2667 0 90)
			(size 0.3048 0.381)
			(layers "F.Cu" "F.Mask" "F.Paste")
			(net "P5E_PEX3_STN5_TX_C_DP<86>")
		)
	)
)
